FILE_TYPE = MULTI_PHYS_TABLE;

PART 'PRTR5V0U2X'

{========================================================================================}
:VALUE        | PART_TYPE | MATERIAL | PART_NUMBER    = STANDARD | LIFECYCLE      | PART_NUMBER   | JEDEC_TYPE | DESCRIPTION                          | MANUFTR | MANUF_PN     | RD_CMPLS_LVL | CMPLS_LVL | FROM_PJ    | CLASS | DIP_SMD | DATA                 | EE_CHECK_LIST | FP_ECN | PSL | CREATOR | STATUS | CREATEDAY  ;
{========================================================================================}
 'PRTR5V0U2X' | 'SMLF'    | 'IC'     | 'AL5V0U2X000'(!) = ''       | ''               | 'AL5V0U2X000' |'SOT143XB'| 'IC OTHER (4P) PRTR5V0U2X (SOT143B)' | 'NXP'   | 'PRTR5V0U2X' | 'EP(V1)'     | 'EP(V1)'  | 'S1M-MARK' | 'IC'  | ''      | 'NXP_PRTR5V0U2X.pdf' | ''            | ''     | ''  | ''      | ''     | '20140312'
 'PRTR5V0U2X' | 'SMLF'    | 'EMPTY'  | 'AL5V0U2X000'(!) = ''       | ''               | 'AL5V0U2X000' |'SOT143XB'| 'IC OTHER (4P) PRTR5V0U2X (SOT143B)' | 'NXP'   | 'PRTR5V0U2X' | 'EP(V1)'     | 'EP(V1)'  | 'S1M-MARK' | 'IC'  | ''      | 'NXP_PRTR5V0U2X.pdf' | ''            | ''     | ''  | ''      | ''     | '20140312'

END_PART

END.

